# BASEBOARD_FAB2 (Tioga Pass) — schematic netlist excerpt (pin names and nets, part order shuffled) for the footprints in the layout excerpt that follows; sources: Cadence DE-HDL packaged netlist, KiCad conversion of Wiwynn_Tioga_Pass_MB.brd

R1D31  RES  6.19K 1% CHIP  pkg 0402  page 199 : A = PWRGD_P12V_R ; B = GND
R2T63  RES  0.0 5% EMPTY  pkg 0402  page 93 : A = FM_CPU_ERR1_LVT3_N ; B = FM_CPU_ERR1_PCH_N
R7A15  RES  2.2 5% EMPTY  pkg 0402  page 232 : A = VR_PVPP_DEF_SNUB ; B = GND

(kicad_pcb
	(version 20260206)
	(generator "pcbnew")
	(generator_version "10.0")
	(general
		(thickness 1.6)
		(legacy_teardrops no)
	)
	(paper "A4")
	(title_block
		(title "Wiwynn_Tioga_Pass_MB.brd")
		(comment 1 "Tioga Pass / footprints 1680-1682 of 4770")
	)
	(layers
		(0 "F.Cu" signal "TOP")
		(4 "In1.Cu" signal "L2GND")
		(6 "In2.Cu" signal "L3")
		(8 "In3.Cu" signal "L4GND")
		(10 "In4.Cu" signal "L5")
		(12 "In5.Cu" signal "L6GND")
		(14 "In6.Cu" signal "L7VCC")
		(16 "In7.Cu" signal "L8VCC")
		(18 "In8.Cu" signal "L9GND")
		(20 "In9.Cu" signal "L10")
		(22 "In10.Cu" signal "L11GND")
		(24 "In11.Cu" signal "L12")
		(26 "In12.Cu" signal "L13GND")
		(2 "B.Cu" signal "BOTTOM")
		(9 "F.Adhes" user "F.Adhesive")
		(11 "B.Adhes" user "B.Adhesive")
		(13 "F.Paste" user "Package Geometry/Pastemask Top")
		(15 "B.Paste" user "Package Geometry/Pastemask Bottom")
		(5 "F.SilkS" user "Ref Des/Silkscreen Top")
		(7 "B.SilkS" user "Ref Des/Silkscreen Bottom")
		(1 "F.Mask" user "Board Geometry/Soldermask Top")
		(3 "B.Mask" user "Board Geometry/Soldermask Bottom")
		(17 "Dwgs.User" user "User.Drawings")
		(19 "Cmts.User" user "User.Comments")
		(21 "Eco1.User" user "User.Eco1")
		(23 "Eco2.User" user "User.Eco2")
		(25 "Edge.Cuts" user "Board Geometry/Outline")
		(27 "Margin" user)
		(31 "F.CrtYd" user "Package Geometry/Place Bound Top")
		(29 "B.CrtYd" user "Package Geometry/Place Bound Bottom")
		(35 "F.Fab" user "Ref Des/Assembly Top")
		(33 "B.Fab" user "Ref Des/Assembly Bottom")
	)
	(footprint ""
		(layer "F.Cu")
		(at 405.384 -46.8249 180)
		(property "Reference" "R2T63"
			(at 0 0 180)
			(layer "F.SilkS")
			(hide yes)
			(effects
				(font
					(size 1.27 1.27)
				)
			)
		)
		(property "Value" ""
			(at 0 0 180)
			(layer "F.Fab")
			(effects
				(font
					(size 1.27 1.27)
				)
			)
		)
		(duplicate_pad_numbers_are_jumpers no)
		(fp_poly
			(pts
				(xy -0.2794 -0.1016) (xy 0.2794 -0.1016) (xy 0.2794 0.9906) (xy -0.2794 0.9906)
			)
			(stroke
				(width 0)
				(type default)
			)
			(fill no)
			(layer "F.CrtYd")
		)
		(fp_line
			(start 0.2794 0.9906)
			(end 0.2794 -0.1016)
			(stroke
				(width 0.1)
				(type default)
			)
			(layer "F.Fab")
		)
		(fp_line
			(start 0.2794 -0.1016)
			(end -0.2794 -0.1016)
			(stroke
				(width 0.1)
				(type default)
			)
			(layer "F.Fab")
		)
		(fp_line
			(start -0.2794 0.9906)
			(end 0.2794 0.9906)
			(stroke
				(width 0.1)
				(type default)
			)
			(layer "F.Fab")
		)
		(fp_line
			(start -0.2794 -0.1016)
			(end -0.2794 0.9906)
			(stroke
				(width 0.1)
				(type default)
			)
			(layer "F.Fab")
		)
		(pad "1" smd rect
			(at 0 0 180)
			(size 0.508 0.508)
			(layers "F.Cu" "F.Mask" "F.Paste")
			(net "FM_CPU_ERR1_LVT3_N")
		)
		(pad "2" smd rect
			(at 0 0.889 180)
			(size 0.508 0.508)
			(layers "F.Cu" "F.Mask" "F.Paste")
			(net "FM_CPU_ERR1_PCH_N")
		)
		(zone
			(layer "F.Cu")
			(hatch none 0.5)
			(connect_pads
				(clearance 0)
			)
			(min_thickness 0.25)
			(keepout
				(tracks not_allowed)
				(vias allowed)
				(pads allowed)
				(copperpour not_allowed)
				(footprints allowed)
			)
			(placement
				(enabled no)
				(sheetname "")
			)
			(fill
				(thermal_gap 0.5)
				(thermal_bridge_width 0.5)
				(island_removal_mode 0)
			)
			(polygon
				(pts
					(xy 405.638 -47.4599) (xy 405.13 -47.4599) (xy 405.13 -47.0789) (xy 405.638 -47.0789)
				)
			)
		)
		(zone
			(layer "F.Cu")
			(hatch none 0.5)
			(connect_pads
				(clearance 0)
			)
			(min_thickness 0.25)
			(keepout
				(tracks allowed)
				(vias not_allowed)
				(pads allowed)
				(copperpour not_allowed)
				(footprints allowed)
			)
			(placement
				(enabled no)
				(sheetname "")
			)
			(fill
				(thermal_gap 0.5)
				(thermal_bridge_width 0.5)
				(island_removal_mode 0)
			)
			(polygon
				(pts
					(xy 405.638 -47.0789) (xy 405.13 -47.0789) (xy 405.13 -47.4599) (xy 405.638 -47.4599)
				)
			)
		)
	)
	(footprint ""
		(layer "F.Cu")
		(at 342.646 -137.1727 90)
		(property "Reference" "R7A15"
			(at 0 0 90)
			(layer "F.SilkS")
			(hide yes)
			(effects
				(font
					(size 1.27 1.27)
				)
			)
		)
		(property "Value" ""
			(at 0 0 90)
			(layer "F.Fab")
			(effects
				(font
					(size 1.27 1.27)
				)
			)
		)
		(duplicate_pad_numbers_are_jumpers no)
		(fp_poly
			(pts
				(xy -0.2794 -0.1016) (xy 0.2794 -0.1016) (xy 0.2794 0.9906) (xy -0.2794 0.9906)
			)
			(stroke
				(width 0)
				(type default)
			)
			(fill no)
			(layer "F.CrtYd")
		)
		(fp_line
			(start 0.2794 -0.1016)
			(end -0.2794 -0.1016)
			(stroke
				(width 0.1)
				(type default)
			)
			(layer "F.Fab")
		)
		(fp_line
			(start -0.2794 -0.1016)
			(end -0.2794 0.9906)
			(stroke
				(width 0.1)
				(type default)
			)
			(layer "F.Fab")
		)
		(fp_line
			(start 0.2794 0.9906)
			(end 0.2794 -0.1016)
			(stroke
				(width 0.1)
				(type default)
			)
			(layer "F.Fab")
		)
		(fp_line
			(start -0.2794 0.9906)
			(end 0.2794 0.9906)
			(stroke
				(width 0.1)
				(type default)
			)
			(layer "F.Fab")
		)
		(pad "1" smd rect
			(at 0 0 90)
			(size 0.508 0.508)
			(layers "F.Cu" "F.Mask" "F.Paste")
			(net "VR_PVPP_DEF_SNUB")
		)
		(pad "2" smd rect
			(at 0 0.889 90)
			(size 0.508 0.508)
			(layers "F.Cu" "F.Mask" "F.Paste")
			(net "GND")
		)
		(zone
			(layer "F.Cu")
			(hatch none 0.5)
			(connect_pads
				(clearance 0)
			)
			(min_thickness 0.25)
			(keepout
				(tracks allowed)
				(vias not_allowed)
				(pads allowed)
				(copperpour not_allowed)
				(footprints allowed)
			)
			(placement
				(enabled no)
				(sheetname "")
			)
			(fill
				(thermal_gap 0.5)
				(thermal_bridge_width 0.5)
				(island_removal_mode 0)
			)
			(polygon
				(pts
					(xy 342.9 -136.9187) (xy 342.9 -137.4267) (xy 343.281 -137.4267) (xy 343.281 -136.9187)
				)
			)
		)
		(zone
			(layer "F.Cu")
			(hatch none 0.5)
			(connect_pads
				(clearance 0)
			)
			(min_thickness 0.25)
			(keepout
				(tracks not_allowed)
				(vias allowed)
				(pads allowed)
				(copperpour not_allowed)
				(footprints allowed)
			)
			(placement
				(enabled no)
				(sheetname "")
			)
			(fill
				(thermal_gap 0.5)
				(thermal_bridge_width 0.5)
				(island_removal_mode 0)
			)
			(polygon
				(pts
					(xy 343.281 -136.9187) (xy 343.281 -137.4267) (xy 342.9 -137.4267) (xy 342.9 -136.9187)
				)
			)
		)
	)
	(footprint ""
		(layer "F.Cu")
		(at 14.224 -77.216 180)
		(property "Reference" "R1D31"
			(at 0 0 180)
			(layer "F.SilkS")
			(hide yes)
			(effects
				(font
					(size 1.27 1.27)
				)
			)
		)
		(property "Value" ""
			(at 0 0 180)
			(layer "F.Fab")
			(effects
				(font
					(size 1.27 1.27)
				)
			)
		)
		(duplicate_pad_numbers_are_jumpers no)
		(fp_rect
			(start 0.2794 0.9906)
			(end -0.2794 -0.1016)
			(stroke
				(width 0)
				(type default)
			)
			(fill no)
			(layer "F.CrtYd")
		)
		(fp_line
			(start 0.2794 0.9906)
			(end 0.2794 -0.1016)
			(stroke
				(width 0.1)
				(type default)
			)
			(layer "F.Fab")
		)
		(fp_line
			(start 0.2794 -0.1016)
			(end -0.2794 -0.1016)
			(stroke
				(width 0.1)
				(type default)
			)
			(layer "F.Fab")
		)
		(fp_line
			(start -0.2794 0.9906)
			(end 0.2794 0.9906)
			(stroke
				(width 0.1)
				(type default)
			)
			(layer "F.Fab")
		)
		(fp_line
			(start -0.2794 -0.1016)
			(end -0.2794 0.9906)
			(stroke
				(width 0.1)
				(type default)
			)
			(layer "F.Fab")
		)
		(pad "1" smd rect
			(at 0 0 180)
			(size 0.508 0.508)
			(layers "F.Cu" "F.Mask" "F.Paste")
			(net "PWRGD_P12V_R")
		)
		(pad "2" smd rect
			(at 0 0.889 180)
			(size 0.508 0.508)
			(layers "F.Cu" "F.Mask" "F.Paste")
			(net "GND")
		)
		(zone
			(layer "F.Cu")
			(hatch none 0.5)
			(connect_pads
				(clearance 0)
			)
			(min_thickness 0.25)
			(keepout
				(tracks not_allowed)
				(vias allowed)
				(pads allowed)
				(copperpour not_allowed)
				(footprints allowed)
			)
			(placement
				(enabled no)
				(sheetname "")
			)
			(fill
				(thermal_gap 0.5)
				(thermal_bridge_width 0.5)
				(island_removal_mode 0)
			)
			(polygon
				(pts
					(xy 13.97 -77.851) (xy 13.97 -77.47) (xy 14.478 -77.47) (xy 14.478 -77.851)
				)
			)
		)
		(zone
			(layer "F.Cu")
			(hatch none 0.5)
			(connect_pads
				(clearance 0)
			)
			(min_thickness 0.25)
			(keepout
				(tracks allowed)
				(vias not_allowed)
				(pads allowed)
				(copperpour not_allowed)
				(footprints allowed)
			)
			(placement
				(enabled no)
				(sheetname "")
			)
			(fill
				(thermal_gap 0.5)
				(thermal_bridge_width 0.5)
				(island_removal_mode 0)
			)
			(polygon
				(pts
					(xy 13.97 -77.851) (xy 13.97 -77.47) (xy 14.478 -77.47) (xy 14.478 -77.851)
				)
			)
		)
	)
)
